# BASEBOARD_FAB2 (Tioga Pass) — schematic netlist excerpt (pin names and nets, part order shuffled) for the footprints in the layout excerpt that follows; sources: Cadence DE-HDL packaged netlist, KiCad conversion of Wiwynn_Tioga_Pass_MB.brd

J4B2  SCONN120_H61426002  CONN  pkg SM  page 193
  IOA1  = P12V_STBY
  IOA2  = P12V_STBY
  IOA3  = P12V_STBY
  IOA4  = P12V_STBY
  IOA5  = P12V_STBY
  IOA6  = P12V_STBY
  IOA7  = P12V_STBY
  IOA8  = P12V_STBY
  IOA9  = GND
  IOA10  = GND
  IOA11  = P3V3_STBY
  IOA12  = GND
  IOA13  = P5V_STBY
  IOA14  = GND
  IOA15  = FM_P1V8MCP_CPU1_EN
  IOA16  = FM_PVCCIOMCP_CPU1_EN
  IOA17  = GND
  IOA18  = SMB_VR_STBY_LVC3_SCL
  IOA19  = SVID_ALERT0_CPU1_R_N
  IOA20  = SVID_CLK0_CPU1_R
  IOB1  = P12V_STBY
  IOB2  = P12V_STBY
  IOB3  = P12V_STBY
  IOB4  = P12V_STBY
  IOB5  = P12V_STBY
  IOB6  = P12V_STBY
  IOB7  = P12V_STBY
  IOB8  = P12V_STBY
  IOB9  = GND
  IOB10  = GND
  IOB11  = P3V3_STBY
  IOB12  = GND
  IOB13  = P5V_STBY
  IOB14  = GND
  IOB15  = PWRGD_P1V8MCP_CPU1
  IOB16  = PWRGD_PVCCIOMCP_CPU1
  IOB17  = GND
  IOB18  = SMB_VR_STBY_LVC3_SDA
  IOB19  = SVID_ALERT1_CPU1_R_N
  IOB20  = SVID_DIO0_CPU1_R
  IOC1  = GND
  IOC2  = GND
  IOC3  = GND
  IOC4  = GND
  IOC5  = GND
  IOC6  = GND
  IOC7  = GND
  IOC8  = GND
  IOC9  = GND
  IOC10  = GND
  IOC11  = P3V3_STBY
  IOC12  = GND
  IOC13  = P5V_STBY
  IOC14  = GND
  IOC15  = GND
  IOC16  = GND
  IOC17  = PVCCIOMCP_CPU1
  IOC18  = PVCCIOMCP_CPU1
  IOC19  = PVCCIOMCP_CPU1
  IOC20  = FM_PVCCMCP_CPU1_EN
  IOD1  = P3V3
  IOD2  = GND
  IOD3  = GND
  IOD4  = GND
  IOD5  = GND
  IOD6  = GND
  IOD7  = GND
  IOD8  = GND
  IOD9  = GND
  IOD10  = GND
  IOD11  = GND
  IOD12  = GND
  IOD13  = GND
  IOD14  = GND
  IOD15  = GND
  IOD16  = GND
  IOD17  = PVCCIOMCP_CPU1
  IOD18  = PVCCIOMCP_CPU1
  IOD19  = PVCCIOMCP_CPU1
  IOD20  = PWRGD_PVCCMCP_CPU1
  IOE1  = FM_CPU1_VRM_322M_156M_OSC_EN
  IOE2  = GND
  IOE3  = GND
  IOE4  = GND
  IOE5  = GND
  IOE6  = GND
  IOE7  = GND
  IOE8  = VSENSE_PVCCIOMCP_CPU1_SKT_VSEN
  IOE9  = GND
  IOE10  = VR_PVCCIOMCP_CPU1_XADDR1
  IOE11  = GND
  IOE12  = GND
  IOE13  = GND
  IOE14  = GND
  IOE15  = PVCCIOMCP_CPU1
  IOE16  = PVCCIOMCP_CPU1
  IOE17  = PVCCIOMCP_CPU1
  IOE18  = PVCCIOMCP_CPU1
  IOE19  = PVCCIOMCP_CPU1
  IOE20  = SVID_CLK1_CPU1_R
  IOF1  = PVCCIO_CPU1
  IOF2  = GND
  IOF3  = GND
  IOF4  = GND
  IOF5  = GND
  IOF6  = GND
  IOF7  = GND
  IOF8  = VSENSE_PVCCIOMCP_CPU1_SKT_VRTN
  IOF9  = GND
  IOF10  = VR_PVCCMCP_CPU1_XADDR2
  IOF11  = GND
  IOF12  = GND
  IOF13  = GND
  IOF14  = GND
  IOF15  = PVCCIOMCP_CPU1
  IOF16  = PVCCIOMCP_CPU1
  IOF17  = PVCCIOMCP_CPU1
  IOF18  = PVCCIOMCP_CPU1
  IOF19  = PVCCIOMCP_CPU1
  IOF20  = SVID_DIO1_CPU1_R

(kicad_pcb
	(version 20260206)
	(generator "pcbnew")
	(generator_version "10.0")
	(general
		(thickness 1.6)
		(legacy_teardrops no)
	)
	(paper "A4")
	(title_block
		(title "Wiwynn_Tioga_Pass_MB.brd")
		(comment 1 "Tioga Pass / footprint 858 of 4770 (J4B2), pads 103-122 of 122")
	)
	(layers
		(0 "F.Cu" signal "TOP")
		(4 "In1.Cu" signal "L2GND")
		(6 "In2.Cu" signal "L3")
		(8 "In3.Cu" signal "L4GND")
		(10 "In4.Cu" signal "L5")
		(12 "In5.Cu" signal "L6GND")
		(14 "In6.Cu" signal "L7VCC")
		(16 "In7.Cu" signal "L8VCC")
		(18 "In8.Cu" signal "L9GND")
		(20 "In9.Cu" signal "L10")
		(22 "In10.Cu" signal "L11GND")
		(24 "In11.Cu" signal "L12")
		(26 "In12.Cu" signal "L13GND")
		(2 "B.Cu" signal "BOTTOM")
		(9 "F.Adhes" user "F.Adhesive")
		(11 "B.Adhes" user "B.Adhesive")
		(13 "F.Paste" user "Package Geometry/Pastemask Top")
		(15 "B.Paste" user "Package Geometry/Pastemask Bottom")
		(5 "F.SilkS" user "Ref Des/Silkscreen Top")
		(7 "B.SilkS" user "Ref Des/Silkscreen Bottom")
		(1 "F.Mask" user "Board Geometry/Soldermask Top")
		(3 "B.Mask" user "Board Geometry/Soldermask Bottom")
		(17 "Dwgs.User" user "User.Drawings")
		(19 "Cmts.User" user "User.Comments")
		(21 "Eco1.User" user "User.Eco1")
		(23 "Eco2.User" user "User.Eco2")
		(25 "Edge.Cuts" user "Board Geometry/Outline")
		(27 "Margin" user)
		(31 "F.CrtYd" user "Package Geometry/Place Bound Top")
		(29 "B.CrtYd" user "Package Geometry/Place Bound Bottom")
		(35 "F.Fab" user "Ref Des/Assembly Top")
		(33 "B.Fab" user "Ref Des/Assembly Bottom")
	)
	(footprint ""
		(layer "F.Cu")
		(at 164.615114 -115.55095 90)
		(property "Reference" "J4B2"
			(at -3.59283 -5.018024 90)
			(unlocked yes)
			(layer "F.SilkS")
			(effects
				(font
					(size 0.7874 0.5842)
					(thickness 0.1524)
				)
			)
		)
		(property "Value" ""
			(at 0 0 90)
			(layer "F.Fab")
			(effects
				(font
					(size 1.27 1.27)
				)
			)
		)
		(duplicate_pad_numbers_are_jumpers no)
		(pad "F1" smd circle
			(at -6.35 0 90)
			(size 0.635 0.635)
			(layers "F.Cu" "F.Mask" "F.Paste")
			(net "PVCCIO_CPU1")
		)
		(pad "F2" smd circle
			(at -6.35 1.27 90)
			(size 0.635 0.635)
			(layers "F.Cu" "F.Mask" "F.Paste")
			(net "GND")
		)
		(pad "F3" smd circle
			(at -6.35 2.54 90)
			(size 0.635 0.635)
			(layers "F.Cu" "F.Mask" "F.Paste")
			(net "GND")
		)
		(pad "F4" smd circle
			(at -6.35 3.81 90)
			(size 0.635 0.635)
			(layers "F.Cu" "F.Mask" "F.Paste")
			(net "GND")
		)
		(pad "F5" smd circle
			(at -6.35 5.08 90)
			(size 0.635 0.635)
			(layers "F.Cu" "F.Mask" "F.Paste")
			(net "GND")
		)
		(pad "F6" smd circle
			(at -6.35 6.35 90)
			(size 0.635 0.635)
			(layers "F.Cu" "F.Mask" "F.Paste")
			(net "GND")
		)
		(pad "F7" smd circle
			(at -6.35 7.62 90)
			(size 0.635 0.635)
			(layers "F.Cu" "F.Mask" "F.Paste")
			(net "GND")
		)
		(pad "F8" smd circle
			(at -6.35 8.89 90)
			(size 0.635 0.635)
			(layers "F.Cu" "F.Mask" "F.Paste")
			(net "VSENSE_PVCCIOMCP_CPU1_SKT_VRTN")
		)
		(pad "F9" smd circle
			(at -6.35 10.16 90)
			(size 0.635 0.635)
			(layers "F.Cu" "F.Mask" "F.Paste")
			(net "GND")
		)
		(pad "F10" smd circle
			(at -6.35 11.43 90)
			(size 0.635 0.635)
			(layers "F.Cu" "F.Mask" "F.Paste")
			(net "VR_PVCCMCP_CPU1_XADDR2")
		)
		(pad "F11" smd circle
			(at -6.35 12.7 90)
			(size 0.635 0.635)
			(layers "F.Cu" "F.Mask" "F.Paste")
			(net "GND")
		)
		(pad "F12" smd circle
			(at -6.35 13.97 90)
			(size 0.635 0.635)
			(layers "F.Cu" "F.Mask" "F.Paste")
			(net "GND")
		)
		(pad "F13" smd circle
			(at -6.35 15.24 90)
			(size 0.635 0.635)
			(layers "F.Cu" "F.Mask" "F.Paste")
			(net "GND")
		)
		(pad "F14" smd circle
			(at -6.35 16.51 90)
			(size 0.635 0.635)
			(layers "F.Cu" "F.Mask" "F.Paste")
			(net "GND")
		)
		(pad "F15" smd circle
			(at -6.35 17.78 90)
			(size 0.635 0.635)
			(layers "F.Cu" "F.Mask" "F.Paste")
			(net "PVCCIOMCP_CPU1")
		)
		(pad "F16" smd circle
			(at -6.35 19.05 90)
			(size 0.635 0.635)
			(layers "F.Cu" "F.Mask" "F.Paste")
			(net "PVCCIOMCP_CPU1")
		)
		(pad "F17" smd circle
			(at -6.35 20.32 90)
			(size 0.635 0.635)
			(layers "F.Cu" "F.Mask" "F.Paste")
			(net "PVCCIOMCP_CPU1")
		)
		(pad "F18" smd circle
			(at -6.35 21.59 90)
			(size 0.635 0.635)
			(layers "F.Cu" "F.Mask" "F.Paste")
			(net "PVCCIOMCP_CPU1")
		)
		(pad "F19" smd circle
			(at -6.35 22.86 90)
			(size 0.635 0.635)
			(layers "F.Cu" "F.Mask" "F.Paste")
			(net "PVCCIOMCP_CPU1")
		)
		(pad "F20" smd circle
			(at -6.35 24.13 90)
			(size 0.635 0.635)
			(layers "F.Cu" "F.Mask" "F.Paste")
			(net "SVID_DIO1_CPU1_R")
		)
	)
)
